# BASEBOARD_FAB2 (Tioga Pass) — schematic netlist excerpt (pin names and nets, part order shuffled) for the footprints in the layout excerpt that follows; sources: Cadence DE-HDL packaged netlist, KiCad conversion of Wiwynn_Tioga_Pass_MB.brd

C25W39  CAP  4.7UF 6.3V 10% X6S  pkg 0603  page 149 : A = VCC_A_1V1 ; B = GND
R9P16  RES  0.0 5% CHIP  pkg 0402  page 199 : A = FM_P12V_HSC_ADR2 ; B = AGND_HSC

Q8F2  FET_N  2N7002 FET  pkg SOT23LF  page 170
  GATE  = FM_FAST_PROCHOT_EN_N
  SRC  = GND
  DRN  = FM_FAST_PROCHOT_EN

(kicad_pcb
	(version 20260206)
	(generator "pcbnew")
	(generator_version "10.0")
	(general
		(thickness 1.6)
		(legacy_teardrops no)
	)
	(paper "A4")
	(title_block
		(title "Wiwynn_Tioga_Pass_MB.brd")
		(comment 1 "Tioga Pass / footprints 2455-2457 of 4770")
	)
	(layers
		(0 "F.Cu" signal "TOP")
		(4 "In1.Cu" signal "L2GND")
		(6 "In2.Cu" signal "L3")
		(8 "In3.Cu" signal "L4GND")
		(10 "In4.Cu" signal "L5")
		(12 "In5.Cu" signal "L6GND")
		(14 "In6.Cu" signal "L7VCC")
		(16 "In7.Cu" signal "L8VCC")
		(18 "In8.Cu" signal "L9GND")
		(20 "In9.Cu" signal "L10")
		(22 "In10.Cu" signal "L11GND")
		(24 "In11.Cu" signal "L12")
		(26 "In12.Cu" signal "L13GND")
		(2 "B.Cu" signal "BOTTOM")
		(9 "F.Adhes" user "F.Adhesive")
		(11 "B.Adhes" user "B.Adhesive")
		(13 "F.Paste" user "Package Geometry/Pastemask Top")
		(15 "B.Paste" user "Package Geometry/Pastemask Bottom")
		(5 "F.SilkS" user "Ref Des/Silkscreen Top")
		(7 "B.SilkS" user "Ref Des/Silkscreen Bottom")
		(1 "F.Mask" user "Board Geometry/Soldermask Top")
		(3 "B.Mask" user "Board Geometry/Soldermask Bottom")
		(17 "Dwgs.User" user "User.Drawings")
		(19 "Cmts.User" user "User.Comments")
		(21 "Eco1.User" user "User.Eco1")
		(23 "Eco2.User" user "User.Eco2")
		(25 "Edge.Cuts" user "Board Geometry/Outline")
		(27 "Margin" user)
		(31 "F.CrtYd" user "Package Geometry/Place Bound Top")
		(29 "B.CrtYd" user "Package Geometry/Place Bound Bottom")
		(35 "F.Fab" user "Ref Des/Assembly Top")
		(33 "B.Fab" user "Ref Des/Assembly Bottom")
	)
	(footprint ""
		(layer "B.Cu")
		(at 419.6715 -71.9455)
		(property "Reference" "Q8F2"
			(at 1.16967 4.13004 270)
			(unlocked yes)
			(layer "B.SilkS")
			(effects
				(font
					(size 0.7874 0.5842)
					(thickness 0.1524)
				)
				(justify left mirror)
			)
		)
		(property "Value" ""
			(at 0 0 0)
			(layer "B.Fab")
			(effects
				(font
					(size 1.27 1.27)
				)
				(justify mirror)
			)
		)
		(duplicate_pad_numbers_are_jumpers no)
		(fp_line
			(start -1.778 -0.5715)
			(end -1.778 0.3175)
			(stroke
				(width 0.1524)
				(type default)
			)
			(layer "B.SilkS")
		)
		(fp_line
			(start -1.778 2.4765)
			(end -1.778 1.5875)
			(stroke
				(width 0.1524)
				(type default)
			)
			(layer "B.SilkS")
		)
		(fp_line
			(start -0.9525 -0.5715)
			(end -1.778 -0.5715)
			(stroke
				(width 0.1524)
				(type default)
			)
			(layer "B.SilkS")
		)
		(fp_line
			(start -0.9525 2.4765)
			(end -1.778 2.4765)
			(stroke
				(width 0.1524)
				(type default)
			)
			(layer "B.SilkS")
		)
		(fp_line
			(start -0.381 0.635)
			(end -0.381 1.27)
			(stroke
				(width 0.1524)
				(type default)
			)
			(layer "B.SilkS")
		)
		(fp_circle
			(center 0.9525 -0.9271)
			(end 1.0795 -0.9271)
			(stroke
				(width 0.254)
				(type default)
			)
			(fill no)
			(layer "B.SilkS")
		)
		(fp_poly
			(pts
				(xy -1.778 2.4765) (xy -0.381 2.4765) (xy -0.381 -0.5715) (xy -1.778 -0.5715)
			)
			(stroke
				(width 0)
				(type default)
			)
			(fill no)
			(layer "B.CrtYd")
		)
		(fp_line
			(start -1.778 -0.5715)
			(end -0.381 -0.5715)
			(stroke
				(width 0.1)
				(type default)
			)
			(layer "B.Fab")
		)
		(fp_line
			(start -1.778 2.4765)
			(end -1.778 -0.5715)
			(stroke
				(width 0.1)
				(type default)
			)
			(layer "B.Fab")
		)
		(fp_line
			(start -0.381 -0.5715)
			(end -0.381 2.4765)
			(stroke
				(width 0.1)
				(type default)
			)
			(layer "B.Fab")
		)
		(fp_line
			(start -0.381 2.4765)
			(end -1.778 2.4765)
			(stroke
				(width 0.1)
				(type default)
			)
			(layer "B.Fab")
		)
		(fp_circle
			(center 0.9525 -0.9271)
			(end 1.0795 -0.9271)
			(stroke
				(width 0.254)
				(type default)
			)
			(fill no)
			(layer "B.Fab")
		)
		(pad "1" smd rect
			(at 0 0 180)
			(size 1.143 0.508)
			(layers "B.Cu" "B.Mask" "B.Paste")
			(net "FM_FAST_PROCHOT_EN_N")
		)
		(pad "2" smd rect
			(at 0 1.905 180)
			(size 1.143 0.508)
			(layers "B.Cu" "B.Mask" "B.Paste")
			(net "GND")
		)
		(pad "3" smd rect
			(at -2.159 0.9525 180)
			(size 1.143 0.508)
			(layers "B.Cu" "B.Mask" "B.Paste")
			(net "FM_FAST_PROCHOT_EN")
		)
	)
	(footprint ""
		(layer "B.Cu")
		(at 20.3454 -78.0542 -90)
		(property "Reference" "R9P16"
			(at 0 0 90)
			(layer "B.SilkS")
			(hide yes)
			(effects
				(font
					(size 1.27 1.27)
				)
				(justify mirror)
			)
		)
		(property "Value" ""
			(at 0 0 90)
			(layer "B.Fab")
			(effects
				(font
					(size 1.27 1.27)
				)
				(justify mirror)
			)
		)
		(duplicate_pad_numbers_are_jumpers no)
		(fp_rect
			(start 0.2794 -0.1016)
			(end -0.2794 0.9906)
			(stroke
				(width 0)
				(type default)
			)
			(fill no)
			(layer "B.CrtYd")
		)
		(fp_line
			(start -0.2794 0.9906)
			(end -0.2794 -0.1016)
			(stroke
				(width 0.1)
				(type default)
			)
			(layer "B.Fab")
		)
		(fp_line
			(start 0.2794 0.9906)
			(end -0.2794 0.9906)
			(stroke
				(width 0.1)
				(type default)
			)
			(layer "B.Fab")
		)
		(fp_line
			(start -0.2794 -0.1016)
			(end 0.2794 -0.1016)
			(stroke
				(width 0.1)
				(type default)
			)
			(layer "B.Fab")
		)
		(fp_line
			(start 0.2794 -0.1016)
			(end 0.2794 0.9906)
			(stroke
				(width 0.1)
				(type default)
			)
			(layer "B.Fab")
		)
		(pad "1" smd rect
			(at 0 0 90)
			(size 0.508 0.508)
			(layers "B.Cu" "B.Mask" "B.Paste")
			(net "FM_P12V_HSC_ADR2")
		)
		(pad "2" smd rect
			(at 0 0.889 90)
			(size 0.508 0.508)
			(layers "B.Cu" "B.Mask" "B.Paste")
			(net "AGND_HSC")
		)
		(zone
			(layer "B.Cu")
			(hatch none 0.5)
			(connect_pads
				(clearance 0)
			)
			(min_thickness 0.25)
			(keepout
				(tracks not_allowed)
				(vias allowed)
				(pads allowed)
				(copperpour not_allowed)
				(footprints allowed)
			)
			(placement
				(enabled no)
				(sheetname "")
			)
			(fill
				(thermal_gap 0.5)
				(thermal_bridge_width 0.5)
				(island_removal_mode 0)
			)
			(polygon
				(pts
					(xy 20.0914 -77.8002) (xy 20.0914 -78.3082) (xy 19.7104 -78.3082) (xy 19.7104 -77.8002)
				)
			)
		)
		(zone
			(layer "B.Cu")
			(hatch none 0.5)
			(connect_pads
				(clearance 0)
			)
			(min_thickness 0.25)
			(keepout
				(tracks allowed)
				(vias not_allowed)
				(pads allowed)
				(copperpour not_allowed)
				(footprints allowed)
			)
			(placement
				(enabled no)
				(sheetname "")
			)
			(fill
				(thermal_gap 0.5)
				(thermal_bridge_width 0.5)
				(island_removal_mode 0)
			)
			(polygon
				(pts
					(xy 20.0914 -77.8002) (xy 20.0914 -78.3082) (xy 19.7104 -78.3082) (xy 19.7104 -77.8002)
				)
			)
		)
	)
	(footprint ""
		(layer "B.Cu")
		(at 416.3695 -30.988 90)
		(property "Reference" "C25W39"
			(at -0.97536 0.76708 180)
			(unlocked yes)
			(layer "B.SilkS")
			(effects
				(font
					(size 0.4064 0.254)
					(thickness 0.1524)
				)
				(justify mirror)
			)
		)
		(property "Value" ""
			(at 0 0 90)
			(layer "B.Fab")
			(effects
				(font
					(size 1.27 1.27)
				)
				(justify mirror)
			)
		)
		(duplicate_pad_numbers_are_jumpers no)
		(fp_poly
			(pts
				(xy 0.4953 -0.2032) (xy -0.4953 -0.2032) (xy -0.4953 1.6002) (xy 0.4953 1.6002)
			)
			(stroke
				(width 0)
				(type default)
			)
			(fill no)
			(layer "B.CrtYd")
		)
		(fp_line
			(start 0.4953 -0.2032)
			(end -0.4953 -0.2032)
			(stroke
				(width 0.1)
				(type default)
			)
			(layer "B.Fab")
		)
		(fp_line
			(start -0.4953 -0.2032)
			(end -0.4953 1.6002)
			(stroke
				(width 0.1)
				(type default)
			)
			(layer "B.Fab")
		)
		(fp_line
			(start 0.4953 1.6002)
			(end 0.4953 -0.2032)
			(stroke
				(width 0.1)
				(type default)
			)
			(layer "B.Fab")
		)
		(fp_line
			(start -0.4953 1.6002)
			(end 0.4953 1.6002)
			(stroke
				(width 0.1)
				(type default)
			)
			(layer "B.Fab")
		)
		(pad "1" smd rect
			(at 0 0 270)
			(size 0.762 0.889)
			(layers "B.Cu" "B.Mask" "B.Paste")
			(net "VCC_A_1V1")
		)
		(pad "2" smd rect
			(at 0 1.397 270)
			(size 0.762 0.889)
			(layers "B.Cu" "B.Mask" "B.Paste")
			(net "GND")
		)
		(zone
			(layer "B.Cu")
			(hatch none 0.5)
			(connect_pads
				(clearance 0)
			)
			(min_thickness 0.25)
			(keepout
				(tracks not_allowed)
				(vias allowed)
				(pads allowed)
				(copperpour not_allowed)
				(footprints allowed)
			)
			(placement
				(enabled no)
				(sheetname "")
			)
			(fill
				(thermal_gap 0.5)
				(thermal_bridge_width 0.5)
				(island_removal_mode 0)
			)
			(polygon
				(pts
					(xy 416.814 -31.369) (xy 416.814 -30.607) (xy 417.322 -30.607) (xy 417.322 -31.369)
				)
			)
		)
	)
)
